(kicad_pcb
	(version 20260206)
	(generator "pcbnew")
	(generator_version "10.0")
	(general
		(thickness 1.6)
		(legacy_teardrops no)
	)
	(paper "A4")
	(title_block
		(title "03242023_DA0F0TMBIJ0_F0T_Motherboard_J_brd_V01_OCP.brd")
		(comment 1 "Grand Teton / footprints 2822-2827 of 6105")
	)
	(layers
		(0 "F.Cu" signal "TOP")
		(4 "In1.Cu" signal "GND")
		(6 "In2.Cu" signal "IN1")
		(8 "In3.Cu" signal "GND1")
		(10 "In4.Cu" signal "IN2")
		(12 "In5.Cu" signal "GND2")
		(14 "In6.Cu" signal "IN3")
		(16 "In7.Cu" signal "GND3")
		(18 "In8.Cu" signal "VCC")
		(20 "In9.Cu" signal "VCC1")
		(22 "In10.Cu" signal "GND4")
		(24 "In11.Cu" signal "IN4")
		(26 "In12.Cu" signal "GND5")
		(28 "In13.Cu" signal "IN5")
		(30 "In14.Cu" signal "GND6")
		(32 "In15.Cu" signal "IN6")
		(34 "In16.Cu" signal "GND7")
		(2 "B.Cu" signal "BOTTOM")
		(9 "F.Adhes" user "F.Adhesive")
		(11 "B.Adhes" user "B.Adhesive")
		(13 "F.Paste" user "Package Geometry/Pastemask Top")
		(15 "B.Paste" user "Package Geometry/Pastemask Bottom")
		(5 "F.SilkS" user "Ref Des/Silkscreen Top")
		(7 "B.SilkS" user "Ref Des/Silkscreen Bottom")
		(1 "F.Mask" user "Board Geometry/Soldermask Top")
		(3 "B.Mask" user "Board Geometry/Soldermask Bottom")
		(17 "Dwgs.User" user "User.Drawings")
		(19 "Cmts.User" user "User.Comments")
		(21 "Eco1.User" user "User.Eco1")
		(23 "Eco2.User" user "User.Eco2")
		(25 "Edge.Cuts" user "Board Geometry/Outline")
		(27 "Margin" user)
		(31 "F.CrtYd" user "Package Geometry/Place Bound Top")
		(29 "B.CrtYd" user "Package Geometry/Place Bound Bottom")
		(35 "F.Fab" user "Ref Des/Assembly Top")
		(33 "B.Fab" user "Ref Des/Assembly Bottom")
	)
	(footprint ""
		(layer "F.Cu")
		(at 99.62388 -81.585308)
		(property "Reference" "Q83"
			(at 0.37592 -1.93675 0)
			(unlocked yes)
			(layer "F.SilkS")
			(effects
				(font
					(size 0.635 0.4064)
					(thickness 0.1524)
				)
			)
		)
		(property "Value" ""
			(at 0 0 0)
			(layer "F.Fab")
			(effects
				(font
					(size 1.27 1.27)
				)
			)
		)
		(duplicate_pad_numbers_are_jumpers no)
		(fp_line
			(start -1.332738 -1.100074)
			(end -0.4826 -1.100074)
			(stroke
				(width 0.1524)
				(type default)
			)
			(layer "F.SilkS")
		)
		(fp_line
			(start -1.332738 1.100074)
			(end -1.332738 -1.100074)
			(stroke
				(width 0.1524)
				(type default)
			)
			(layer "F.SilkS")
		)
		(fp_line
			(start -0.4826 -1.100074)
			(end 0 -0.541274)
			(stroke
				(width 0.1524)
				(type default)
			)
			(layer "F.SilkS")
		)
		(fp_line
			(start 0 -0.541274)
			(end 0.4826 -1.100074)
			(stroke
				(width 0.1524)
				(type default)
			)
			(layer "F.SilkS")
		)
		(fp_line
			(start 0.4826 -1.100074)
			(end 1.332738 -1.100074)
			(stroke
				(width 0.1524)
				(type default)
			)
			(layer "F.SilkS")
		)
		(fp_line
			(start 1.332738 -1.100074)
			(end 1.332738 1.100074)
			(stroke
				(width 0.1524)
				(type default)
			)
			(layer "F.SilkS")
		)
		(fp_line
			(start 1.332738 1.100074)
			(end -1.332738 1.100074)
			(stroke
				(width 0.1524)
				(type default)
			)
			(layer "F.SilkS")
		)
		(fp_poly
			(pts
				(xy -2.1082 -1.763014) (xy -1.406144 -1.411986) (xy -2.1082 -1.060958)
			)
			(stroke
				(width 0)
				(type default)
			)
			(fill yes)
			(layer "F.SilkS")
		)
		(fp_line
			(start -0.674878 -1.100074)
			(end 0.674878 -1.100074)
			(stroke
				(width 0.1)
				(type default)
			)
			(layer "F.Fab")
		)
		(fp_line
			(start -0.674878 1.100074)
			(end -0.674878 -1.100074)
			(stroke
				(width 0.1)
				(type default)
			)
			(layer "F.Fab")
		)
		(fp_line
			(start 0.674878 -1.100074)
			(end 0.674878 1.100074)
			(stroke
				(width 0.1)
				(type default)
			)
			(layer "F.Fab")
		)
		(fp_line
			(start 0.674878 1.100074)
			(end -0.674878 1.100074)
			(stroke
				(width 0.1)
				(type default)
			)
			(layer "F.Fab")
		)
		(fp_poly
			(pts
				(xy -2.2352 -0.298958) (xy -2.2352 -1.001014) (xy -1.533144 -0.649986)
			)
			(stroke
				(width 0)
				(type default)
			)
			(fill yes)
			(layer "F.Fab")
		)
		(pad "1" smd rect
			(at -0.94996 -0.649986 90)
			(size 0.4318 0.508)
			(layers "F.Cu" "F.Mask" "F.Paste")
			(net "GND")
		)
		(pad "2" smd rect
			(at -0.94996 0 90)
			(size 0.4318 0.508)
			(layers "F.Cu" "F.Mask" "F.Paste")
			(net "PWRGD_PVCCIN_CPU0")
		)
		(pad "3" smd rect
			(at -0.94996 0.649986 90)
			(size 0.4318 0.508)
			(layers "F.Cu" "F.Mask" "F.Paste")
			(net "LED_PWRGD_PVCCIN_CPU1_D")
		)
		(pad "4" smd rect
			(at 0.94996 0.649986 90)
			(size 0.4318 0.508)
			(layers "F.Cu" "F.Mask" "F.Paste")
			(net "GND")
		)
		(pad "5" smd rect
			(at 0.94996 0 90)
			(size 0.4318 0.508)
			(layers "F.Cu" "F.Mask" "F.Paste")
			(net "PWRGD_PVCCIN_CPU1")
		)
		(pad "6" smd rect
			(at 0.94996 -0.649986 90)
			(size 0.4318 0.508)
			(layers "F.Cu" "F.Mask" "F.Paste")
			(net "LED_PWRGD_PVCCIN_CPU0_D")
		)
	)
	(footprint ""
		(layer "F.Cu")
		(at 193.893186 -438.17413 90)
		(property "Reference" "R2941"
			(at 0 0 90)
			(layer "F.SilkS")
			(hide yes)
			(effects
				(font
					(size 1.27 1.27)
				)
			)
		)
		(property "Value" ""
			(at 0 0 90)
			(layer "F.Fab")
			(effects
				(font
					(size 1.27 1.27)
				)
			)
		)
		(duplicate_pad_numbers_are_jumpers no)
		(fp_line
			(start 0.7874 -0.4064)
			(end 0.7874 0.4064)
			(stroke
				(width 0.1524)
				(type default)
			)
			(layer "F.SilkS")
		)
		(fp_line
			(start -0.7874 -0.4064)
			(end 0.7874 -0.4064)
			(stroke
				(width 0.1524)
				(type default)
			)
			(layer "F.SilkS")
		)
		(fp_line
			(start 0.7874 0.4064)
			(end -0.7874 0.4064)
			(stroke
				(width 0.1524)
				(type default)
			)
			(layer "F.SilkS")
		)
		(fp_line
			(start -0.7874 0.4064)
			(end -0.7874 -0.4064)
			(stroke
				(width 0.1524)
				(type default)
			)
			(layer "F.SilkS")
		)
		(fp_line
			(start -0.12065 -0.305054)
			(end -0.12065 -0.2794)
			(stroke
				(width 0.1)
				(type default)
			)
			(layer "F.Fab")
		)
		(fp_line
			(start -0.67945 -0.305054)
			(end -0.12065 -0.305054)
			(stroke
				(width 0.1)
				(type default)
			)
			(layer "F.Fab")
		)
		(fp_line
			(start 0.67945 -0.3048)
			(end 0.67945 0.3048)
			(stroke
				(width 0.1)
				(type default)
			)
			(layer "F.Fab")
		)
		(fp_line
			(start 0.12065 -0.3048)
			(end 0.67945 -0.3048)
			(stroke
				(width 0.1)
				(type default)
			)
			(layer "F.Fab")
		)
		(fp_line
			(start 0.12065 -0.2794)
			(end 0.12065 -0.3048)
			(stroke
				(width 0.1)
				(type default)
			)
			(layer "F.Fab")
		)
		(fp_line
			(start -0.12065 -0.2794)
			(end 0.12065 -0.2794)
			(stroke
				(width 0.1)
				(type default)
			)
			(layer "F.Fab")
		)
		(fp_line
			(start 0.120396 0.2794)
			(end -0.12065 0.2794)
			(stroke
				(width 0.1)
				(type default)
			)
			(layer "F.Fab")
		)
		(fp_line
			(start -0.12065 0.2794)
			(end -0.12065 0.3048)
			(stroke
				(width 0.1)
				(type default)
			)
			(layer "F.Fab")
		)
		(fp_line
			(start 0.67945 0.3048)
			(end 0.120396 0.3048)
			(stroke
				(width 0.1)
				(type default)
			)
			(layer "F.Fab")
		)
		(fp_line
			(start 0.120396 0.3048)
			(end 0.120396 0.2794)
			(stroke
				(width 0.1)
				(type default)
			)
			(layer "F.Fab")
		)
		(fp_line
			(start -0.12065 0.3048)
			(end -0.67945 0.3048)
			(stroke
				(width 0.1)
				(type default)
			)
			(layer "F.Fab")
		)
		(fp_line
			(start -0.67945 0.3048)
			(end -0.67945 -0.305054)
			(stroke
				(width 0.1)
				(type default)
			)
			(layer "F.Fab")
		)
		(pad "1" smd circle
			(at -0.40005 0 90)
			(size 0 0)
			(layers "F.Cu" "F.Mask" "F.Paste")
			(net "FM_GPU_HSC_EN")
		)
		(pad "2" smd circle
			(at 0.40005 0 90)
			(size 0 0)
			(layers "F.Cu" "F.Mask" "F.Paste")
			(net "GND")
		)
	)
	(footprint ""
		(layer "F.Cu")
		(at 100.94849 -92.87256)
		(property "Reference" "Q78"
			(at 1.61544 -0.762508 0)
			(unlocked yes)
			(layer "F.SilkS")
			(effects
				(font
					(size 0.7874 0.5842)
					(thickness 0.1524)
				)
				(justify left)
			)
		)
		(property "Value" ""
			(at 0 0 0)
			(layer "F.Fab")
			(effects
				(font
					(size 1.27 1.27)
				)
			)
		)
		(duplicate_pad_numbers_are_jumpers no)
		(fp_line
			(start -1.332738 -1.100074)
			(end -0.4826 -1.100074)
			(stroke
				(width 0.1524)
				(type default)
			)
			(layer "F.SilkS")
		)
		(fp_line
			(start -1.332738 1.100074)
			(end -1.332738 -1.100074)
			(stroke
				(width 0.1524)
				(type default)
			)
			(layer "F.SilkS")
		)
		(fp_line
			(start -0.4826 -1.100074)
			(end 0 -0.541274)
			(stroke
				(width 0.1524)
				(type default)
			)
			(layer "F.SilkS")
		)
		(fp_line
			(start 0 -0.541274)
			(end 0.4826 -1.100074)
			(stroke
				(width 0.1524)
				(type default)
			)
			(layer "F.SilkS")
		)
		(fp_line
			(start 0.4826 -1.100074)
			(end 1.332738 -1.100074)
			(stroke
				(width 0.1524)
				(type default)
			)
			(layer "F.SilkS")
		)
		(fp_line
			(start 1.332738 -1.100074)
			(end 1.332738 1.100074)
			(stroke
				(width 0.1524)
				(type default)
			)
			(layer "F.SilkS")
		)
		(fp_line
			(start 1.332738 1.100074)
			(end -1.332738 1.100074)
			(stroke
				(width 0.1524)
				(type default)
			)
			(layer "F.SilkS")
		)
		(fp_poly
			(pts
				(xy -1.809242 -1.854962) (xy -1.561084 -1.110488) (xy -2.305812 -1.358646)
			)
			(stroke
				(width 0)
				(type default)
			)
			(fill yes)
			(layer "F.SilkS")
		)
		(fp_line
			(start -0.674878 -1.100074)
			(end 0.674878 -1.100074)
			(stroke
				(width 0.1)
				(type default)
			)
			(layer "F.Fab")
		)
		(fp_line
			(start -0.674878 1.100074)
			(end -0.674878 -1.100074)
			(stroke
				(width 0.1)
				(type default)
			)
			(layer "F.Fab")
		)
		(fp_line
			(start 0.674878 -1.100074)
			(end 0.674878 1.100074)
			(stroke
				(width 0.1)
				(type default)
			)
			(layer "F.Fab")
		)
		(fp_line
			(start 0.674878 1.100074)
			(end -0.674878 1.100074)
			(stroke
				(width 0.1)
				(type default)
			)
			(layer "F.Fab")
		)
		(fp_poly
			(pts
				(xy -2.2352 -0.298958) (xy -2.2352 -1.001014) (xy -1.533144 -0.649986)
			)
			(stroke
				(width 0)
				(type default)
			)
			(fill yes)
			(layer "F.Fab")
		)
		(pad "1" smd rect
			(at -0.94996 -0.649986 90)
			(size 0.4318 0.508)
			(layers "F.Cu" "F.Mask" "F.Paste")
			(net "GND")
		)
		(pad "2" smd rect
			(at -0.94996 0 90)
			(size 0.4318 0.508)
			(layers "F.Cu" "F.Mask" "F.Paste")
			(net "FM_PCH_SLP_S3_N")
		)
		(pad "3" smd rect
			(at -0.94996 0.649986 90)
			(size 0.4318 0.508)
			(layers "F.Cu" "F.Mask" "F.Paste")
			(net "LED_PWRGD_PS_PWROK_PLD_D")
		)
		(pad "4" smd rect
			(at 0.94996 0.649986 90)
			(size 0.4318 0.508)
			(layers "F.Cu" "F.Mask" "F.Paste")
			(net "GND")
		)
		(pad "5" smd rect
			(at 0.94996 0 90)
			(size 0.4318 0.508)
			(layers "F.Cu" "F.Mask" "F.Paste")
			(net "PWRGD_PS_PWROK_PLD")
		)
		(pad "6" smd rect
			(at 0.94996 -0.649986 90)
			(size 0.4318 0.508)
			(layers "F.Cu" "F.Mask" "F.Paste")
			(net "LED_FM_PCH_SLP_S3_N_D")
		)
	)
	(footprint ""
		(layer "F.Cu")
		(at 197.41388 -102.415848)
		(property "Reference" "R1843"
			(at 0 0 0)
			(layer "F.SilkS")
			(hide yes)
			(effects
				(font
					(size 1.27 1.27)
				)
			)
		)
		(property "Value" ""
			(at 0 0 0)
			(layer "F.Fab")
			(effects
				(font
					(size 1.27 1.27)
				)
			)
		)
		(duplicate_pad_numbers_are_jumpers no)
		(fp_line
			(start -0.7874 -0.4064)
			(end 0.7874 -0.4064)
			(stroke
				(width 0.1524)
				(type default)
			)
			(layer "F.SilkS")
		)
		(fp_line
			(start -0.7874 0.4064)
			(end -0.7874 -0.4064)
			(stroke
				(width 0.1524)
				(type default)
			)
			(layer "F.SilkS")
		)
		(fp_line
			(start 0.7874 -0.4064)
			(end 0.7874 0.4064)
			(stroke
				(width 0.1524)
				(type default)
			)
			(layer "F.SilkS")
		)
		(fp_line
			(start 0.7874 0.4064)
			(end -0.7874 0.4064)
			(stroke
				(width 0.1524)
				(type default)
			)
			(layer "F.SilkS")
		)
		(fp_line
			(start -0.67945 -0.305054)
			(end -0.12065 -0.305054)
			(stroke
				(width 0.1)
				(type default)
			)
			(layer "F.Fab")
		)
		(fp_line
			(start -0.67945 0.3048)
			(end -0.67945 -0.305054)
			(stroke
				(width 0.1)
				(type default)
			)
			(layer "F.Fab")
		)
		(fp_line
			(start -0.12065 -0.305054)
			(end -0.12065 -0.2794)
			(stroke
				(width 0.1)
				(type default)
			)
			(layer "F.Fab")
		)
		(fp_line
			(start -0.12065 -0.2794)
			(end 0.12065 -0.2794)
			(stroke
				(width 0.1)
				(type default)
			)
			(layer "F.Fab")
		)
		(fp_line
			(start -0.12065 0.2794)
			(end -0.12065 0.3048)
			(stroke
				(width 0.1)
				(type default)
			)
			(layer "F.Fab")
		)
		(fp_line
			(start -0.12065 0.3048)
			(end -0.67945 0.3048)
			(stroke
				(width 0.1)
				(type default)
			)
			(layer "F.Fab")
		)
		(fp_line
			(start 0.120396 0.2794)
			(end -0.12065 0.2794)
			(stroke
				(width 0.1)
				(type default)
			)
			(layer "F.Fab")
		)
		(fp_line
			(start 0.120396 0.3048)
			(end 0.120396 0.2794)
			(stroke
				(width 0.1)
				(type default)
			)
			(layer "F.Fab")
		)
		(fp_line
			(start 0.12065 -0.3048)
			(end 0.67945 -0.3048)
			(stroke
				(width 0.1)
				(type default)
			)
			(layer "F.Fab")
		)
		(fp_line
			(start 0.12065 -0.2794)
			(end 0.12065 -0.3048)
			(stroke
				(width 0.1)
				(type default)
			)
			(layer "F.Fab")
		)
		(fp_line
			(start 0.67945 -0.3048)
			(end 0.67945 0.3048)
			(stroke
				(width 0.1)
				(type default)
			)
			(layer "F.Fab")
		)
		(fp_line
			(start 0.67945 0.3048)
			(end 0.120396 0.3048)
			(stroke
				(width 0.1)
				(type default)
			)
			(layer "F.Fab")
		)
		(pad "1" smd circle
			(at -0.40005 0)
			(size 0 0)
			(layers "F.Cu" "F.Mask" "F.Paste")
			(net "RST_PFR_OVR_RTC_R")
		)
		(pad "2" smd circle
			(at 0.40005 0)
			(size 0 0)
			(layers "F.Cu" "F.Mask" "F.Paste")
			(net "RST_PFR_OVR_RTC")
		)
	)
	(footprint ""
		(layer "F.Cu")
		(at 109.14888 -53.304948)
		(property "Reference" "R1349"
			(at 0 0 0)
			(layer "F.SilkS")
			(hide yes)
			(effects
				(font
					(size 1.27 1.27)
				)
			)
		)
		(property "Value" ""
			(at 0 0 0)
			(layer "F.Fab")
			(effects
				(font
					(size 1.27 1.27)
				)
			)
		)
		(duplicate_pad_numbers_are_jumpers no)
		(fp_line
			(start -0.7874 -0.4064)
			(end 0.7874 -0.4064)
			(stroke
				(width 0.1524)
				(type default)
			)
			(layer "F.SilkS")
		)
		(fp_line
			(start -0.7874 0.4064)
			(end -0.7874 -0.4064)
			(stroke
				(width 0.1524)
				(type default)
			)
			(layer "F.SilkS")
		)
		(fp_line
			(start 0.7874 -0.4064)
			(end 0.7874 0.4064)
			(stroke
				(width 0.1524)
				(type default)
			)
			(layer "F.SilkS")
		)
		(fp_line
			(start 0.7874 0.4064)
			(end -0.7874 0.4064)
			(stroke
				(width 0.1524)
				(type default)
			)
			(layer "F.SilkS")
		)
		(fp_line
			(start -0.67945 -0.305054)
			(end -0.12065 -0.305054)
			(stroke
				(width 0.1)
				(type default)
			)
			(layer "F.Fab")
		)
		(fp_line
			(start -0.67945 0.3048)
			(end -0.67945 -0.305054)
			(stroke
				(width 0.1)
				(type default)
			)
			(layer "F.Fab")
		)
		(fp_line
			(start -0.12065 -0.305054)
			(end -0.12065 -0.2794)
			(stroke
				(width 0.1)
				(type default)
			)
			(layer "F.Fab")
		)
		(fp_line
			(start -0.12065 -0.2794)
			(end 0.12065 -0.2794)
			(stroke
				(width 0.1)
				(type default)
			)
			(layer "F.Fab")
		)
		(fp_line
			(start -0.12065 0.2794)
			(end -0.12065 0.3048)
			(stroke
				(width 0.1)
				(type default)
			)
			(layer "F.Fab")
		)
		(fp_line
			(start -0.12065 0.3048)
			(end -0.67945 0.3048)
			(stroke
				(width 0.1)
				(type default)
			)
			(layer "F.Fab")
		)
		(fp_line
			(start 0.120396 0.2794)
			(end -0.12065 0.2794)
			(stroke
				(width 0.1)
				(type default)
			)
			(layer "F.Fab")
		)
		(fp_line
			(start 0.120396 0.3048)
			(end 0.120396 0.2794)
			(stroke
				(width 0.1)
				(type default)
			)
			(layer "F.Fab")
		)
		(fp_line
			(start 0.12065 -0.3048)
			(end 0.67945 -0.3048)
			(stroke
				(width 0.1)
				(type default)
			)
			(layer "F.Fab")
		)
		(fp_line
			(start 0.12065 -0.2794)
			(end 0.12065 -0.3048)
			(stroke
				(width 0.1)
				(type default)
			)
			(layer "F.Fab")
		)
		(fp_line
			(start 0.67945 -0.3048)
			(end 0.67945 0.3048)
			(stroke
				(width 0.1)
				(type default)
			)
			(layer "F.Fab")
		)
		(fp_line
			(start 0.67945 0.3048)
			(end 0.120396 0.3048)
			(stroke
				(width 0.1)
				(type default)
			)
			(layer "F.Fab")
		)
		(pad "1" smd circle
			(at -0.40005 0)
			(size 0 0)
			(layers "F.Cu" "F.Mask" "F.Paste")
			(net "JTAG_DBP_TCK_PCH_R")
		)
		(pad "2" smd circle
			(at 0.40005 0)
			(size 0 0)
			(layers "F.Cu" "F.Mask" "F.Paste")
			(net "JTAG_DBP_TCK_PCH")
		)
	)
	(footprint ""
		(layer "F.Cu")
		(at 171.50588 -126.964948 90)
		(property "Reference" "R1411"
			(at 0 0 90)
			(layer "F.SilkS")
			(hide yes)
			(effects
				(font
					(size 1.27 1.27)
				)
			)
		)
		(property "Value" ""
			(at 0 0 90)
			(layer "F.Fab")
			(effects
				(font
					(size 1.27 1.27)
				)
			)
		)
		(duplicate_pad_numbers_are_jumpers no)
		(fp_line
			(start 0.7874 -0.4064)
			(end 0.7874 0.4064)
			(stroke
				(width 0.1524)
				(type default)
			)
			(layer "F.SilkS")
		)
		(fp_line
			(start -0.7874 -0.4064)
			(end 0.7874 -0.4064)
			(stroke
				(width 0.1524)
				(type default)
			)
			(layer "F.SilkS")
		)
		(fp_line
			(start 0.7874 0.4064)
			(end -0.7874 0.4064)
			(stroke
				(width 0.1524)
				(type default)
			)
			(layer "F.SilkS")
		)
		(fp_line
			(start -0.7874 0.4064)
			(end -0.7874 -0.4064)
			(stroke
				(width 0.1524)
				(type default)
			)
			(layer "F.SilkS")
		)
		(fp_line
			(start -0.12065 -0.305054)
			(end -0.12065 -0.2794)
			(stroke
				(width 0.1)
				(type default)
			)
			(layer "F.Fab")
		)
		(fp_line
			(start -0.67945 -0.305054)
			(end -0.12065 -0.305054)
			(stroke
				(width 0.1)
				(type default)
			)
			(layer "F.Fab")
		)
		(fp_line
			(start 0.67945 -0.3048)
			(end 0.67945 0.3048)
			(stroke
				(width 0.1)
				(type default)
			)
			(layer "F.Fab")
		)
		(fp_line
			(start 0.12065 -0.3048)
			(end 0.67945 -0.3048)
			(stroke
				(width 0.1)
				(type default)
			)
			(layer "F.Fab")
		)
		(fp_line
			(start 0.12065 -0.2794)
			(end 0.12065 -0.3048)
			(stroke
				(width 0.1)
				(type default)
			)
			(layer "F.Fab")
		)
		(fp_line
			(start -0.12065 -0.2794)
			(end 0.12065 -0.2794)
			(stroke
				(width 0.1)
				(type default)
			)
			(layer "F.Fab")
		)
		(fp_line
			(start 0.120396 0.2794)
			(end -0.12065 0.2794)
			(stroke
				(width 0.1)
				(type default)
			)
			(layer "F.Fab")
		)
		(fp_line
			(start -0.12065 0.2794)
			(end -0.12065 0.3048)
			(stroke
				(width 0.1)
				(type default)
			)
			(layer "F.Fab")
		)
		(fp_line
			(start 0.67945 0.3048)
			(end 0.120396 0.3048)
			(stroke
				(width 0.1)
				(type default)
			)
			(layer "F.Fab")
		)
		(fp_line
			(start 0.120396 0.3048)
			(end 0.120396 0.2794)
			(stroke
				(width 0.1)
				(type default)
			)
			(layer "F.Fab")
		)
		(fp_line
			(start -0.12065 0.3048)
			(end -0.67945 0.3048)
			(stroke
				(width 0.1)
				(type default)
			)
			(layer "F.Fab")
		)
		(fp_line
			(start -0.67945 0.3048)
			(end -0.67945 -0.305054)
			(stroke
				(width 0.1)
				(type default)
			)
			(layer "F.Fab")
		)
		(pad "1" smd circle
			(at -0.40005 0 90)
			(size 0 0)
			(layers "F.Cu" "F.Mask" "F.Paste")
			(net "FM_PVCCFA_EHV_FIVRA_CPU0_R_EN")
		)
		(pad "2" smd circle
			(at 0.40005 0 90)
			(size 0 0)
			(layers "F.Cu" "F.Mask" "F.Paste")
			(net "GND")
		)
	)
)
